(kicad_pcb
	(version 20260206)
	(generator "pcbnew")
	(generator_version "10.0")
	(general
		(thickness 1.6)
		(legacy_teardrops no)
	)
	(paper "A4")
	(title_block
		(title "04192023_DAF0TMB3IC0_F0TG_MB_C_brd_V02_OCP.brd")
		(comment 1 "Grand Teton / footprints 5864-5870 of 8354")
	)
	(layers
		(0 "F.Cu" signal "TOP")
		(4 "In1.Cu" signal "GND")
		(6 "In2.Cu" signal "IN1")
		(8 "In3.Cu" signal "GND1")
		(10 "In4.Cu" signal "IN2")
		(12 "In5.Cu" signal "GND2")
		(14 "In6.Cu" signal "IN3")
		(16 "In7.Cu" signal "GND3")
		(18 "In8.Cu" signal "VCC")
		(20 "In9.Cu" signal "VCC1")
		(22 "In10.Cu" signal "GND4")
		(24 "In11.Cu" signal "IN4")
		(26 "In12.Cu" signal "GND5")
		(28 "In13.Cu" signal "IN5")
		(30 "In14.Cu" signal "GND6")
		(32 "In15.Cu" signal "IN6")
		(34 "In16.Cu" signal "GND7")
		(2 "B.Cu" signal "BOTTOM")
		(9 "F.Adhes" user "F.Adhesive")
		(11 "B.Adhes" user "B.Adhesive")
		(13 "F.Paste" user "Package Geometry/Pastemask Top")
		(15 "B.Paste" user "Package Geometry/Pastemask Bottom")
		(5 "F.SilkS" user "Ref Des/Silkscreen Top")
		(7 "B.SilkS" user "Ref Des/Silkscreen Bottom")
		(1 "F.Mask" user "Board Geometry/Soldermask Top")
		(3 "B.Mask" user "Board Geometry/Soldermask Bottom")
		(17 "Dwgs.User" user "User.Drawings")
		(19 "Cmts.User" user "User.Comments")
		(21 "Eco1.User" user "User.Eco1")
		(23 "Eco2.User" user "User.Eco2")
		(25 "Edge.Cuts" user "Board Geometry/Outline")
		(27 "Margin" user)
		(31 "F.CrtYd" user "Package Geometry/Place Bound Top")
		(29 "B.CrtYd" user "Package Geometry/Place Bound Bottom")
		(35 "F.Fab" user "Ref Des/Assembly Top")
		(33 "B.Fab" user "Ref Des/Assembly Bottom")
	)
	(footprint ""
		(layer "B.Cu")
		(at 101.385878 -141.58341 180)
		(property "Reference" "PC6"
			(at 0 0 0)
			(layer "B.SilkS")
			(hide yes)
			(effects
				(font
					(size 1.27 1.27)
				)
				(justify mirror)
			)
		)
		(property "Value" ""
			(at 0 0 0)
			(layer "B.Fab")
			(effects
				(font
					(size 1.27 1.27)
				)
				(justify mirror)
			)
		)
		(duplicate_pad_numbers_are_jumpers no)
		(fp_line
			(start 0.7874 0.4064)
			(end 0.7874 -0.4064)
			(stroke
				(width 0.1524)
				(type default)
			)
			(layer "B.SilkS")
		)
		(fp_line
			(start 0.7874 -0.4064)
			(end -0.7874 -0.4064)
			(stroke
				(width 0.1524)
				(type default)
			)
			(layer "B.SilkS")
		)
		(fp_line
			(start -0.7874 0.4064)
			(end 0.7874 0.4064)
			(stroke
				(width 0.1524)
				(type default)
			)
			(layer "B.SilkS")
		)
		(fp_line
			(start -0.7874 -0.4064)
			(end -0.7874 0.4064)
			(stroke
				(width 0.1524)
				(type default)
			)
			(layer "B.SilkS")
		)
		(fp_line
			(start 0.67945 0.3048)
			(end 0.67945 -0.305054)
			(stroke
				(width 0.1)
				(type default)
			)
			(layer "B.Fab")
		)
		(fp_line
			(start 0.67945 -0.305054)
			(end 0.12065 -0.305054)
			(stroke
				(width 0.1)
				(type default)
			)
			(layer "B.Fab")
		)
		(fp_line
			(start 0.12065 0.3048)
			(end 0.67945 0.3048)
			(stroke
				(width 0.1)
				(type default)
			)
			(layer "B.Fab")
		)
		(fp_line
			(start 0.12065 0.2794)
			(end 0.12065 0.3048)
			(stroke
				(width 0.1)
				(type default)
			)
			(layer "B.Fab")
		)
		(fp_line
			(start 0.12065 -0.2794)
			(end -0.12065 -0.2794)
			(stroke
				(width 0.1)
				(type default)
			)
			(layer "B.Fab")
		)
		(fp_line
			(start 0.12065 -0.305054)
			(end 0.12065 -0.2794)
			(stroke
				(width 0.1)
				(type default)
			)
			(layer "B.Fab")
		)
		(fp_line
			(start -0.120396 0.3048)
			(end -0.120396 0.2794)
			(stroke
				(width 0.1)
				(type default)
			)
			(layer "B.Fab")
		)
		(fp_line
			(start -0.120396 0.2794)
			(end 0.12065 0.2794)
			(stroke
				(width 0.1)
				(type default)
			)
			(layer "B.Fab")
		)
		(fp_line
			(start -0.12065 -0.2794)
			(end -0.12065 -0.3048)
			(stroke
				(width 0.1)
				(type default)
			)
			(layer "B.Fab")
		)
		(fp_line
			(start -0.12065 -0.3048)
			(end -0.67945 -0.3048)
			(stroke
				(width 0.1)
				(type default)
			)
			(layer "B.Fab")
		)
		(fp_line
			(start -0.67945 0.3048)
			(end -0.120396 0.3048)
			(stroke
				(width 0.1)
				(type default)
			)
			(layer "B.Fab")
		)
		(fp_line
			(start -0.67945 -0.3048)
			(end -0.67945 0.3048)
			(stroke
				(width 0.1)
				(type default)
			)
			(layer "B.Fab")
		)
		(pad "1" smd circle
			(at 0.40005 0)
			(size 0 0)
			(layers "B.Cu" "B.Mask" "B.Paste")
			(net "PVDDCR_CPU0_P1_VINSEN")
		)
		(pad "2" smd circle
			(at -0.40005 0)
			(size 0 0)
			(layers "B.Cu" "B.Mask" "B.Paste")
			(net "GND")
		)
	)
	(footprint ""
		(layer "B.Cu")
		(at 382.208278 -137.535158 90)
		(property "Reference" "PC470"
			(at 0 0 90)
			(layer "B.SilkS")
			(hide yes)
			(effects
				(font
					(size 1.27 1.27)
				)
				(justify mirror)
			)
		)
		(property "Value" ""
			(at 0 0 90)
			(layer "B.Fab")
			(effects
				(font
					(size 1.27 1.27)
				)
				(justify mirror)
			)
		)
		(duplicate_pad_numbers_are_jumpers no)
		(fp_line
			(start 0.7874 -0.4064)
			(end -0.7874 -0.4064)
			(stroke
				(width 0.1524)
				(type default)
			)
			(layer "B.SilkS")
		)
		(fp_line
			(start -0.7874 -0.4064)
			(end -0.7874 0.4064)
			(stroke
				(width 0.1524)
				(type default)
			)
			(layer "B.SilkS")
		)
		(fp_line
			(start 0.7874 0.4064)
			(end 0.7874 -0.4064)
			(stroke
				(width 0.1524)
				(type default)
			)
			(layer "B.SilkS")
		)
		(fp_line
			(start -0.7874 0.4064)
			(end 0.7874 0.4064)
			(stroke
				(width 0.1524)
				(type default)
			)
			(layer "B.SilkS")
		)
		(fp_line
			(start 0.67945 -0.305054)
			(end 0.12065 -0.305054)
			(stroke
				(width 0.1)
				(type default)
			)
			(layer "B.Fab")
		)
		(fp_line
			(start 0.12065 -0.305054)
			(end 0.12065 -0.2794)
			(stroke
				(width 0.1)
				(type default)
			)
			(layer "B.Fab")
		)
		(fp_line
			(start -0.12065 -0.3048)
			(end -0.67945 -0.3048)
			(stroke
				(width 0.1)
				(type default)
			)
			(layer "B.Fab")
		)
		(fp_line
			(start -0.67945 -0.3048)
			(end -0.67945 0.3048)
			(stroke
				(width 0.1)
				(type default)
			)
			(layer "B.Fab")
		)
		(fp_line
			(start 0.12065 -0.2794)
			(end -0.12065 -0.2794)
			(stroke
				(width 0.1)
				(type default)
			)
			(layer "B.Fab")
		)
		(fp_line
			(start -0.12065 -0.2794)
			(end -0.12065 -0.3048)
			(stroke
				(width 0.1)
				(type default)
			)
			(layer "B.Fab")
		)
		(fp_line
			(start 0.12065 0.2794)
			(end 0.12065 0.3048)
			(stroke
				(width 0.1)
				(type default)
			)
			(layer "B.Fab")
		)
		(fp_line
			(start -0.120396 0.2794)
			(end 0.12065 0.2794)
			(stroke
				(width 0.1)
				(type default)
			)
			(layer "B.Fab")
		)
		(fp_line
			(start 0.67945 0.3048)
			(end 0.67945 -0.305054)
			(stroke
				(width 0.1)
				(type default)
			)
			(layer "B.Fab")
		)
		(fp_line
			(start 0.12065 0.3048)
			(end 0.67945 0.3048)
			(stroke
				(width 0.1)
				(type default)
			)
			(layer "B.Fab")
		)
		(fp_line
			(start -0.120396 0.3048)
			(end -0.120396 0.2794)
			(stroke
				(width 0.1)
				(type default)
			)
			(layer "B.Fab")
		)
		(fp_line
			(start -0.67945 0.3048)
			(end -0.120396 0.3048)
			(stroke
				(width 0.1)
				(type default)
			)
			(layer "B.Fab")
		)
		(pad "1" smd circle
			(at 0.40005 0 270)
			(size 0 0)
			(layers "B.Cu" "B.Mask" "B.Paste")
			(net "PVDDCR_CPU0_P0_VCCS")
		)
		(pad "2" smd circle
			(at -0.40005 0 270)
			(size 0 0)
			(layers "B.Cu" "B.Mask" "B.Paste")
			(net "GND")
		)
	)
	(footprint ""
		(layer "B.Cu")
		(at 375.597166 -389.49503 180)
		(property "Reference" "C7017"
			(at -1.554988 -3.243072 0)
			(unlocked yes)
			(layer "B.SilkS")
			(effects
				(font
					(size 0.7874 0.5842)
					(thickness 0.1524)
				)
				(justify left mirror)
			)
		)
		(property "Value" ""
			(at 0 0 0)
			(layer "B.Fab")
			(effects
				(font
					(size 1.27 1.27)
				)
				(justify mirror)
			)
		)
		(duplicate_pad_numbers_are_jumpers no)
		(fp_line
			(start 4.84378 -2.150618)
			(end 4.842256 2.163064)
			(stroke
				(width 0.1524)
				(type default)
			)
			(layer "B.SilkS")
		)
		(fp_line
			(start 4.84378 -2.150618)
			(end 4.53898 -2.150618)
			(stroke
				(width 0.1524)
				(type default)
			)
			(layer "B.SilkS")
		)
		(fp_line
			(start 4.83108 2.150364)
			(end 4.447794 2.149348)
			(stroke
				(width 0.1524)
				(type default)
			)
			(layer "B.SilkS")
		)
		(fp_line
			(start 4.69138 -2.150618)
			(end 4.692396 2.161032)
			(stroke
				(width 0.1524)
				(type default)
			)
			(layer "B.SilkS")
		)
		(fp_line
			(start 4.53898 2.15011)
			(end 4.53898 -2.15011)
			(stroke
				(width 0.1524)
				(type default)
			)
			(layer "B.SilkS")
		)
		(fp_line
			(start 4.53898 -2.15011)
			(end -4.53898 -2.15011)
			(stroke
				(width 0.1524)
				(type default)
			)
			(layer "B.SilkS")
		)
		(fp_line
			(start 4.53898 -2.150618)
			(end 4.539742 2.152142)
			(stroke
				(width 0.1524)
				(type default)
			)
			(layer "B.SilkS")
		)
		(fp_line
			(start -4.53898 2.15011)
			(end 4.53898 2.15011)
			(stroke
				(width 0.1524)
				(type default)
			)
			(layer "B.SilkS")
		)
		(fp_line
			(start -4.53898 -2.15011)
			(end -4.53898 2.15011)
			(stroke
				(width 0.1524)
				(type default)
			)
			(layer "B.SilkS")
		)
		(fp_line
			(start 3.64998 2.15011)
			(end 3.64998 -2.15011)
			(stroke
				(width 0.1)
				(type default)
			)
			(layer "B.Fab")
		)
		(fp_line
			(start 3.64998 -2.15011)
			(end -3.64998 -2.15011)
			(stroke
				(width 0.1)
				(type default)
			)
			(layer "B.Fab")
		)
		(fp_line
			(start -3.64998 2.15011)
			(end 3.64998 2.15011)
			(stroke
				(width 0.1)
				(type default)
			)
			(layer "B.Fab")
		)
		(fp_line
			(start -3.64998 -2.15011)
			(end -3.64998 2.15011)
			(stroke
				(width 0.1)
				(type default)
			)
			(layer "B.Fab")
		)
		(fp_text user "+"
			(at 4.233672 -3.049778 180)
			(unlocked yes)
			(layer "B.SilkS")
			(effects
				(font
					(size 1.905 1.4224)
					(thickness 0.1524)
				)
				(justify left mirror)
			)
		)
		(fp_text user "-"
			(at -2.707894 -2.736088 180)
			(unlocked yes)
			(layer "B.SilkS")
			(effects
				(font
					(size 1.905 1.4224)
					(thickness 0.1524)
				)
				(justify left mirror)
			)
		)
		(fp_text user "+"
			(at 6.214872 -0.337058 180)
			(unlocked yes)
			(layer "B.Fab")
			(effects
				(font
					(size 1.905 1.4224)
					(thickness 0.1524)
				)
				(justify left mirror)
			)
		)
		(fp_text user "-"
			(at -4.313174 -0.094488 180)
			(unlocked yes)
			(layer "B.Fab")
			(effects
				(font
					(size 1.905 1.4224)
					(thickness 0.1524)
				)
				(justify left mirror)
			)
		)
		(pad "1" smd rect
			(at 3.199892 0)
			(size 2.413 2.8194)
			(layers "B.Cu" "B.Mask" "B.Paste")
			(net "P0V9_CPU0_RT3_2A")
		)
		(pad "2" smd rect
			(at -3.199892 0)
			(size 2.413 2.8194)
			(layers "B.Cu" "B.Mask" "B.Paste")
			(net "GND")
		)
	)
	(footprint ""
		(layer "B.Cu")
		(at 180.162962 -13.896594 90)
		(property "Reference" "R3778"
			(at 0 0 90)
			(layer "B.SilkS")
			(hide yes)
			(effects
				(font
					(size 1.27 1.27)
				)
				(justify mirror)
			)
		)
		(property "Value" ""
			(at 0 0 90)
			(layer "B.Fab")
			(effects
				(font
					(size 1.27 1.27)
				)
				(justify mirror)
			)
		)
		(duplicate_pad_numbers_are_jumpers no)
		(fp_line
			(start 0.7874 -0.4064)
			(end -0.7874 -0.4064)
			(stroke
				(width 0.1524)
				(type default)
			)
			(layer "B.SilkS")
		)
		(fp_line
			(start -0.7874 -0.4064)
			(end -0.7874 0.4064)
			(stroke
				(width 0.1524)
				(type default)
			)
			(layer "B.SilkS")
		)
		(fp_line
			(start 0.7874 0.4064)
			(end 0.7874 -0.4064)
			(stroke
				(width 0.1524)
				(type default)
			)
			(layer "B.SilkS")
		)
		(fp_line
			(start -0.7874 0.4064)
			(end 0.7874 0.4064)
			(stroke
				(width 0.1524)
				(type default)
			)
			(layer "B.SilkS")
		)
		(fp_line
			(start 0.67945 -0.305054)
			(end 0.12065 -0.305054)
			(stroke
				(width 0.1)
				(type default)
			)
			(layer "B.Fab")
		)
		(fp_line
			(start 0.12065 -0.305054)
			(end 0.12065 -0.2794)
			(stroke
				(width 0.1)
				(type default)
			)
			(layer "B.Fab")
		)
		(fp_line
			(start -0.12065 -0.3048)
			(end -0.67945 -0.3048)
			(stroke
				(width 0.1)
				(type default)
			)
			(layer "B.Fab")
		)
		(fp_line
			(start -0.67945 -0.3048)
			(end -0.67945 0.3048)
			(stroke
				(width 0.1)
				(type default)
			)
			(layer "B.Fab")
		)
		(fp_line
			(start 0.12065 -0.2794)
			(end -0.12065 -0.2794)
			(stroke
				(width 0.1)
				(type default)
			)
			(layer "B.Fab")
		)
		(fp_line
			(start -0.12065 -0.2794)
			(end -0.12065 -0.3048)
			(stroke
				(width 0.1)
				(type default)
			)
			(layer "B.Fab")
		)
		(fp_line
			(start 0.12065 0.2794)
			(end 0.12065 0.3048)
			(stroke
				(width 0.1)
				(type default)
			)
			(layer "B.Fab")
		)
		(fp_line
			(start -0.120396 0.2794)
			(end 0.12065 0.2794)
			(stroke
				(width 0.1)
				(type default)
			)
			(layer "B.Fab")
		)
		(fp_line
			(start 0.67945 0.3048)
			(end 0.67945 -0.305054)
			(stroke
				(width 0.1)
				(type default)
			)
			(layer "B.Fab")
		)
		(fp_line
			(start 0.12065 0.3048)
			(end 0.67945 0.3048)
			(stroke
				(width 0.1)
				(type default)
			)
			(layer "B.Fab")
		)
		(fp_line
			(start -0.120396 0.3048)
			(end -0.120396 0.2794)
			(stroke
				(width 0.1)
				(type default)
			)
			(layer "B.Fab")
		)
		(fp_line
			(start -0.67945 0.3048)
			(end -0.120396 0.3048)
			(stroke
				(width 0.1)
				(type default)
			)
			(layer "B.Fab")
		)
		(pad "1" smd circle
			(at 0.40005 0 270)
			(size 0 0)
			(layers "B.Cu" "B.Mask" "B.Paste")
			(net "FM_SOL_UART_CH_SEL_R")
		)
		(pad "2" smd circle
			(at -0.40005 0 270)
			(size 0 0)
			(layers "B.Cu" "B.Mask" "B.Paste")
			(net "FM_SOL_UART_CH_SEL")
		)
	)
	(footprint ""
		(layer "B.Cu")
		(at 95.248984 -408.517344 90)
		(property "Reference" "C6692"
			(at 0 0 90)
			(layer "B.SilkS")
			(hide yes)
			(effects
				(font
					(size 1.27 1.27)
				)
				(justify mirror)
			)
		)
		(property "Value" ""
			(at 0 0 90)
			(layer "B.Fab")
			(effects
				(font
					(size 1.27 1.27)
				)
				(justify mirror)
			)
		)
		(duplicate_pad_numbers_are_jumpers no)
		(fp_line
			(start 0.299974 -0.150114)
			(end -0.299974 -0.150114)
			(stroke
				(width 0.1)
				(type default)
			)
			(layer "B.Fab")
		)
		(fp_line
			(start -0.299974 -0.150114)
			(end -0.299974 0.150114)
			(stroke
				(width 0.1)
				(type default)
			)
			(layer "B.Fab")
		)
		(fp_line
			(start 0.299974 0.150114)
			(end 0.299974 -0.150114)
			(stroke
				(width 0.1)
				(type default)
			)
			(layer "B.Fab")
		)
		(fp_line
			(start -0.299974 0.150114)
			(end 0.299974 0.150114)
			(stroke
				(width 0.1)
				(type default)
			)
			(layer "B.Fab")
		)
		(pad "1" smd rect
			(at 0.2667 0 270)
			(size 0.3048 0.381)
			(layers "B.Cu" "B.Mask" "B.Paste")
			(net "P5E_CPU1_P1_TX_BUF_C_DN<15>")
		)
		(pad "2" smd rect
			(at -0.2667 0 270)
			(size 0.3048 0.381)
			(layers "B.Cu" "B.Mask" "B.Paste")
			(net "P5E_CPU1_P1_TX_BUF_DN<15>")
		)
	)
	(footprint ""
		(layer "B.Cu")
		(at 245.873778 -315.95568 -90)
		(property "Reference" "PC6512"
			(at 0 0 90)
			(layer "B.SilkS")
			(hide yes)
			(effects
				(font
					(size 1.27 1.27)
				)
				(justify mirror)
			)
		)
		(property "Value" ""
			(at 0 0 90)
			(layer "B.Fab")
			(effects
				(font
					(size 1.27 1.27)
				)
				(justify mirror)
			)
		)
		(duplicate_pad_numbers_are_jumpers no)
		(fp_line
			(start -1.524 0.762)
			(end 1.524 0.762)
			(stroke
				(width 0.1524)
				(type default)
			)
			(layer "B.SilkS")
		)
		(fp_line
			(start 1.524 0.762)
			(end 1.524 -0.762)
			(stroke
				(width 0.1524)
				(type default)
			)
			(layer "B.SilkS")
		)
		(fp_line
			(start -1.524 -0.762)
			(end -1.524 0.762)
			(stroke
				(width 0.1524)
				(type default)
			)
			(layer "B.SilkS")
		)
		(fp_line
			(start 1.524 -0.762)
			(end -1.524 -0.762)
			(stroke
				(width 0.1524)
				(type default)
			)
			(layer "B.SilkS")
		)
		(fp_line
			(start -1.1049 0.724916)
			(end -1.1049 -0.724916)
			(stroke
				(width 0.1)
				(type default)
			)
			(layer "B.Fab")
		)
		(fp_line
			(start 1.1049 0.724916)
			(end -1.1049 0.724916)
			(stroke
				(width 0.1)
				(type default)
			)
			(layer "B.Fab")
		)
		(fp_line
			(start -1.1049 -0.724916)
			(end 1.1049 -0.724916)
			(stroke
				(width 0.1)
				(type default)
			)
			(layer "B.Fab")
		)
		(fp_line
			(start 1.1049 -0.724916)
			(end 1.1049 0.724916)
			(stroke
				(width 0.1)
				(type default)
			)
			(layer "B.Fab")
		)
		(pad "1" smd rect
			(at 0.889 0 270)
			(size 1.016 1.27)
			(layers "B.Cu" "B.Mask" "B.Paste")
			(net "P1V8_CPU0_RT_1D")
		)
		(pad "2" smd rect
			(at -0.889 0 270)
			(size 1.016 1.27)
			(layers "B.Cu" "B.Mask" "B.Paste")
			(net "GND")
		)
	)
	(footprint ""
		(layer "B.Cu")
		(at 161.276284 -192.907412 -90)
		(property "Reference" "R567"
			(at 0 0 90)
			(layer "B.SilkS")
			(hide yes)
			(effects
				(font
					(size 1.27 1.27)
				)
				(justify mirror)
			)
		)
		(property "Value" ""
			(at 0 0 90)
			(layer "B.Fab")
			(effects
				(font
					(size 1.27 1.27)
				)
				(justify mirror)
			)
		)
		(duplicate_pad_numbers_are_jumpers no)
		(fp_line
			(start -0.7874 0.4064)
			(end 0.7874 0.4064)
			(stroke
				(width 0.1524)
				(type default)
			)
			(layer "B.SilkS")
		)
		(fp_line
			(start 0.7874 0.4064)
			(end 0.7874 -0.4064)
			(stroke
				(width 0.1524)
				(type default)
			)
			(layer "B.SilkS")
		)
		(fp_line
			(start -0.7874 -0.4064)
			(end -0.7874 0.4064)
			(stroke
				(width 0.1524)
				(type default)
			)
			(layer "B.SilkS")
		)
		(fp_line
			(start 0.7874 -0.4064)
			(end -0.7874 -0.4064)
			(stroke
				(width 0.1524)
				(type default)
			)
			(layer "B.SilkS")
		)
		(fp_line
			(start -0.67945 0.3048)
			(end -0.120396 0.3048)
			(stroke
				(width 0.1)
				(type default)
			)
			(layer "B.Fab")
		)
		(fp_line
			(start -0.120396 0.3048)
			(end -0.120396 0.2794)
			(stroke
				(width 0.1)
				(type default)
			)
			(layer "B.Fab")
		)
		(fp_line
			(start 0.12065 0.3048)
			(end 0.67945 0.3048)
			(stroke
				(width 0.1)
				(type default)
			)
			(layer "B.Fab")
		)
		(fp_line
			(start 0.67945 0.3048)
			(end 0.67945 -0.305054)
			(stroke
				(width 0.1)
				(type default)
			)
			(layer "B.Fab")
		)
		(fp_line
			(start -0.120396 0.2794)
			(end 0.12065 0.2794)
			(stroke
				(width 0.1)
				(type default)
			)
			(layer "B.Fab")
		)
		(fp_line
			(start 0.12065 0.2794)
			(end 0.12065 0.3048)
			(stroke
				(width 0.1)
				(type default)
			)
			(layer "B.Fab")
		)
		(fp_line
			(start -0.12065 -0.2794)
			(end -0.12065 -0.3048)
			(stroke
				(width 0.1)
				(type default)
			)
			(layer "B.Fab")
		)
		(fp_line
			(start 0.12065 -0.2794)
			(end -0.12065 -0.2794)
			(stroke
				(width 0.1)
				(type default)
			)
			(layer "B.Fab")
		)
		(fp_line
			(start -0.67945 -0.3048)
			(end -0.67945 0.3048)
			(stroke
				(width 0.1)
				(type default)
			)
			(layer "B.Fab")
		)
		(fp_line
			(start -0.12065 -0.3048)
			(end -0.67945 -0.3048)
			(stroke
				(width 0.1)
				(type default)
			)
			(layer "B.Fab")
		)
		(fp_line
			(start 0.12065 -0.305054)
			(end 0.12065 -0.2794)
			(stroke
				(width 0.1)
				(type default)
			)
			(layer "B.Fab")
		)
		(fp_line
			(start 0.67945 -0.305054)
			(end 0.12065 -0.305054)
			(stroke
				(width 0.1)
				(type default)
			)
			(layer "B.Fab")
		)
		(pad "1" smd rect
			(at 0.40005 0 270)
			(size 0.4572 0.508)
			(layers "B.Cu" "B.Mask" "B.Paste")
			(net "I3C_1_SPD_DDRGL_CPU1_SDA")
		)
		(pad "2" smd rect
			(at -0.40005 0 270)
			(size 0.4572 0.508)
			(layers "B.Cu" "B.Mask" "B.Paste")
			(net "I3C_1_SPD_DDRGL_CPU1_R_SDA")
		)
	)
)
